G04 ================== begin FILE IDENTIFICATION RECORD ==================*
G04 Layout Name:  14629-1a.brd*
G04 Film Name:    L3VCC*
G04 File Format:  Gerber RS274X*
G04 File Origin:  Cadence Allegro 16.5-S037*
G04 Origin Date:  Tue Nov 25 11:50:53 2014*
G04 *
G04 Layer:  VIA CLASS/L3VCC*
G04 Layer:  PIN/L3VCC*
G04 Layer:  PACKAGE GEOMETRY/PWRVCC*
G04 Layer:  ETCH/L3VCC*
G04 Layer:  DRAWING FORMAT/LAYER_PCB_STORY*
G04 Layer:  DRAWING FORMAT/LAYER_L3VCC*
G04 *
G04 Offset:    (0.00 0.00)*
G04 Mirror:    No*
G04 Mode:      Negative*
G04 Rotation:  0*
G04 FullContactRelief:  No*
G04 UndefLineWidth:     6.00*
G04 ================== end FILE IDENTIFICATION RECORD ====================*
%FSLAX35Y35*MOIN*%
%IR0*IPPOS*OFA0.00000B0.00000*MIA0B0*SFA1.00000B1.00000*%
%AMMACRO19*
4,1,14,.02931,.01517,
.031499,.00985,
.032731,.004231,
.032968,-.001517,
.032204,-.007219,
.030461,-.012702,
.02931,-.01517,
.03299,-.01885,
.035762,-.012835,
.037448,-.00643,
.037995,.00017,
.037388,.006766,
.035646,.013155,
.03299,.01885,
.02931,.01517,
0.0*
4,1,14,.01517,-.02931,
.00985,-.031499,
.004231,-.032731,
-.001517,-.032968,
-.007219,-.032204,
-.012702,-.030461,
-.01517,-.02931,
-.01885,-.03299,
-.012835,-.035762,
-.00643,-.037448,
.00017,-.037995,
.006766,-.037388,
.013155,-.035646,
.01885,-.03299,
.01517,-.02931,
0.0*
4,1,14,-.02931,-.01517,
-.031499,-.00985,
-.032731,-.004231,
-.032968,.001517,
-.032204,.007219,
-.030461,.012702,
-.02931,.01517,
-.03299,.01885,
-.035762,.012835,
-.037448,.00643,
-.037995,-.00017,
-.037388,-.006766,
-.035646,-.013155,
-.03299,-.01885,
-.02931,-.01517,
0.0*
4,1,14,-.01517,.02931,
-.00985,.031499,
-.004231,.032731,
.001517,.032968,
.007219,.032204,
.012702,.030461,
.01517,.02931,
.01885,.03299,
.012835,.035762,
.00643,.037448,
-.00017,.037995,
-.006766,.037388,
-.013155,.035646,
-.01885,.03299,
-.01517,.02931,
0.0*
%
%ADD19MACRO19*%
%AMMACRO17*
4,1,14,.0267,.01255,
.028474,.007723,
.029382,.002661,
.029398,-.002481,
.02852,-.007549,
.026776,-.012386,
.0267,-.01255,
.03042,-.01628,
.032785,-.01075,
.034154,-.004894,
.034484,.001111,
.033768,.007082,
.032025,.012838,
.03042,.01628,
.0267,.01255,
90.*
4,1,14,.01255,-.0267,
.007723,-.028474,
.002661,-.029382,
-.002481,-.029398,
-.007549,-.02852,
-.012386,-.026776,
-.01255,-.0267,
-.01628,-.03042,
-.01075,-.032785,
-.004894,-.034154,
.001111,-.034484,
.007082,-.033768,
.012838,-.032025,
.01628,-.03042,
.01255,-.0267,
90.*
4,1,14,-.0267,-.01255,
-.028474,-.007723,
-.029382,-.002661,
-.029398,.002481,
-.02852,.007549,
-.026776,.012386,
-.0267,.01255,
-.03042,.01628,
-.032785,.01075,
-.034154,.004894,
-.034484,-.001111,
-.033768,-.007082,
-.032025,-.012838,
-.03042,-.01628,
-.0267,-.01255,
90.*
4,1,14,-.01255,.0267,
-.007723,.028474,
-.002661,.029382,
.002481,.029398,
.007549,.02852,
.012386,.026776,
.01255,.0267,
.01628,.03042,
.01075,.032785,
.004894,.034154,
-.001111,.034484,
-.007082,.033768,
-.012838,.032025,
-.01628,.03042,
-.01255,.0267,
90.*
%
%ADD17MACRO17*%
%AMMACRO16*
4,1,16,.07909,.0508,
.08671,.036294,
.091695,.020686,
.093894,.004449,
.09324,-.011923,
.089753,-.027933,
.083539,-.043094,
.07909,-.0508,
.0827,-.05442,
.090894,-.039233,
.096325,-.022853,
.09883,-.005779,
.098332,.01147,
.094847,.028371,
.088479,.04441,
.0827,.05442,
.07909,.0508,
0.0*
4,1,16,.0508,-.07909,
.036294,-.08671,
.020686,-.091695,
.004449,-.093894,
-.011923,-.09324,
-.027933,-.089753,
-.043094,-.083539,
-.0508,-.07909,
-.05442,-.0827,
-.039233,-.090894,
-.022853,-.096325,
-.005779,-.09883,
.01147,-.098332,
.028371,-.094847,
.04441,-.088479,
.05442,-.0827,
.0508,-.07909,
0.0*
4,1,16,-.07909,-.0508,
-.08671,-.036294,
-.091695,-.020686,
-.093894,-.004449,
-.09324,.011923,
-.089753,.027933,
-.083539,.043094,
-.07909,.0508,
-.0827,.05442,
-.090894,.039233,
-.096325,.022853,
-.09883,.005779,
-.098332,-.01147,
-.094847,-.028371,
-.088479,-.04441,
-.0827,-.05442,
-.07909,-.0508,
0.0*
4,1,16,-.0508,.07909,
-.036294,.08671,
-.020686,.091695,
-.004449,.093894,
.011923,.09324,
.027933,.089753,
.043094,.083539,
.0508,.07909,
.05442,.0827,
.039233,.090894,
.022853,.096325,
.005779,.09883,
-.01147,.098332,
-.028371,.094847,
-.04441,.088479,
-.05442,.0827,
-.0508,.07909,
0.0*
%
%ADD16MACRO16*%
%ADD13C,.036*%
%ADD20C,.064*%
%ADD18C,.069*%
%AMMACRO15*
4,1,15,.00398,.00044,
.003999,.000208,
.004004,-.000025,
.003996,-.000258,
.00398,-.00044,
.00483,-.00129,
.004897,-.001007,
.004947,-.000721,
.004981,-.000432,
.004997,-.000141,
.004997,.000149,
.00498,.00044,
.004946,.000729,
.004895,.001015,
.00483,.00129,
.00398,.00044,
90.*
4,1,15,.00044,-.00398,
.000208,-.003999,
-.000025,-.004004,
-.000258,-.003996,
-.00044,-.00398,
-.00129,-.00483,
-.001007,-.004897,
-.000721,-.004947,
-.000432,-.004981,
-.000141,-.004997,
.000149,-.004997,
.00044,-.00498,
.000729,-.004946,
.001015,-.004895,
.00129,-.00483,
.00044,-.00398,
90.*
4,1,15,-.00398,-.00044,
-.003999,-.000208,
-.004004,.000025,
-.003996,.000258,
-.00398,.00044,
-.00483,.00129,
-.004897,.001007,
-.004947,.000721,
-.004981,.000432,
-.004997,.000141,
-.004997,-.000149,
-.00498,-.00044,
-.004946,-.000729,
-.004895,-.001015,
-.00483,-.00129,
-.00398,-.00044,
90.*
4,1,15,-.00044,.00398,
-.000208,.003999,
.000025,.004004,
.000258,.003996,
.00044,.00398,
.00129,.00483,
.001007,.004897,
.000721,.004947,
.000432,.004981,
.000141,.004997,
-.000149,.004997,
-.00044,.00498,
-.000729,.004946,
-.001015,.004895,
-.00129,.00483,
-.00044,.00398,
90.*
%
%ADD15MACRO15*%
%AMMACRO14*
4,1,15,.00398,.00044,
.003999,.000208,
.004004,-.000025,
.003996,-.000258,
.00398,-.00044,
.00483,-.00129,
.004897,-.001007,
.004947,-.000721,
.004981,-.000432,
.004997,-.000141,
.004997,.000149,
.00498,.00044,
.004946,.000729,
.004895,.001015,
.00483,.00129,
.00398,.00044,
0.0*
4,1,15,.00044,-.00398,
.000208,-.003999,
-.000025,-.004004,
-.000258,-.003996,
-.00044,-.00398,
-.00129,-.00483,
-.001007,-.004897,
-.000721,-.004947,
-.000432,-.004981,
-.000141,-.004997,
.000149,-.004997,
.00044,-.00498,
.000729,-.004946,
.001015,-.004895,
.00129,-.00483,
.00044,-.00398,
0.0*
4,1,15,-.00398,-.00044,
-.003999,-.000208,
-.004004,.000025,
-.003996,.000258,
-.00398,.00044,
-.00483,.00129,
-.004897,.001007,
-.004947,.000721,
-.004981,.000432,
-.004997,.000141,
-.004997,-.000149,
-.00498,-.00044,
-.004946,-.000729,
-.004895,-.001015,
-.00483,-.00129,
-.00398,-.00044,
0.0*
4,1,15,-.00044,.00398,
-.000208,.003999,
.000025,.004004,
.000258,.003996,
.00044,.00398,
.00129,.00483,
.001007,.004897,
.000721,.004947,
.000432,.004981,
.000141,.004997,
-.000149,.004997,
-.00044,.00498,
-.000729,.004946,
-.001015,.004895,
-.00129,.00483,
-.00044,.00398,
0.0*
%
%ADD14MACRO14*%
%ADD10C,.114*%
%ADD21C,.186*%
%AMMACRO12*
4,1,15,.00398,.00044,
.003999,.000208,
.004004,-.000025,
.003996,-.000258,
.00398,-.00044,
.00483,-.00129,
.004897,-.001007,
.004947,-.000721,
.004981,-.000432,
.004997,-.000141,
.004997,.000149,
.00498,.00044,
.004946,.000729,
.004895,.001015,
.00483,.00129,
.00398,.00044,
180.*
4,1,15,.00044,-.00398,
.000208,-.003999,
-.000025,-.004004,
-.000258,-.003996,
-.00044,-.00398,
-.00129,-.00483,
-.001007,-.004897,
-.000721,-.004947,
-.000432,-.004981,
-.000141,-.004997,
.000149,-.004997,
.00044,-.00498,
.000729,-.004946,
.001015,-.004895,
.00129,-.00483,
.00044,-.00398,
180.*
4,1,15,-.00398,-.00044,
-.003999,-.000208,
-.004004,.000025,
-.003996,.000258,
-.00398,.00044,
-.00483,.00129,
-.004897,.001007,
-.004947,.000721,
-.004981,.000432,
-.004997,.000141,
-.004997,-.000149,
-.00498,-.00044,
-.004946,-.000729,
-.004895,-.001015,
-.00483,-.00129,
-.00398,-.00044,
180.*
4,1,15,-.00044,.00398,
-.000208,.003999,
.000025,.004004,
.000258,.003996,
.00044,.00398,
.00129,.00483,
.001007,.004897,
.000721,.004947,
.000432,.004981,
.000141,.004997,
-.000149,.004997,
-.00044,.00498,
-.000729,.004946,
-.001015,.004895,
-.00129,.00483,
-.00044,.00398,
180.*
%
%ADD12MACRO12*%
%AMMACRO11*
4,1,16,.07256,.04427,
.079145,.030998,
.083325,.016783,
.084974,.002059,
.08404,-.012728,
.080553,-.027128,
.074619,-.040704,
.07256,-.04427,
.07619,-.04791,
.083352,-.033952,
.087981,-.018962,
.089937,-.003396,
.089161,.012273,
.085675,.027569,
.079586,.042027,
.07619,.04791,
.07256,.04427,
0.0*
4,1,16,.04427,-.07256,
.030998,-.079145,
.016783,-.083325,
.002059,-.084974,
-.012728,-.08404,
-.027128,-.080553,
-.040704,-.074619,
-.04427,-.07256,
-.04791,-.07619,
-.033952,-.083352,
-.018962,-.087981,
-.003396,-.089937,
.012273,-.089161,
.027569,-.085675,
.042027,-.079586,
.04791,-.07619,
.04427,-.07256,
0.0*
4,1,16,-.07256,-.04427,
-.079145,-.030998,
-.083325,-.016783,
-.084974,-.002059,
-.08404,.012728,
-.080553,.027128,
-.074619,.040704,
-.07256,.04427,
-.07619,.04791,
-.083352,.033952,
-.087981,.018962,
-.089937,.003396,
-.089161,-.012273,
-.085675,-.027569,
-.079586,-.042027,
-.07619,-.04791,
-.07256,-.04427,
0.0*
4,1,16,-.04427,.07256,
-.030998,.079145,
-.016783,.083325,
-.002059,.084974,
.012728,.08404,
.027128,.080553,
.040704,.074619,
.04427,.07256,
.04791,.07619,
.033952,.083352,
.018962,.087981,
.003396,.089937,
-.012273,.089161,
-.027569,.085675,
-.042027,.079586,
-.04791,.07619,
-.04427,.07256,
0.0*
%
%ADD11MACRO11*%
%ADD22C,.02*%
%ADD23C,.006*%
%ADD24C,.18204*%
G75*
%LPD*%
G75*
G36*
G01X-43402Y-6000D02*
X646394D01*
Y478441D01*
X-43402D01*
Y-6000D01*
G37*
%LPC*%
G75*
G36*
G01X3004Y468504D02*
G02X3937Y469437I933J0D01*
G01X636457D01*
G02X637390Y468504I0J-933D01*
G01Y388524D01*
G02X636975Y387748I-933J0D01*
G01X627907Y381704D01*
G02X627390Y381547I-518J776D01*
G01X545905D01*
G03X538965Y374607I1J-6941D01*
G01Y357677D01*
G03X545906Y350736I6941J0D01*
G01X627392D01*
G02X627908Y350580I-1J-933D01*
G01X636975Y344536D01*
G02X637390Y343760I-518J-776D01*
G01Y320720D01*
G02X636457Y319787I-933J0D01*
G01X624645D01*
G03X617705Y312847I1J-6941D01*
G01Y135972D01*
G03X624646Y129031I6941J0D01*
G01X636457D01*
G02X637390Y128098I0J-933D01*
G01Y3937D01*
G02X636457Y3004I-933J0D01*
G01X5374D01*
G02X4975Y3444I-1J400D01*
G03X5000Y3937I-4975J499D01*
G01Y79500D01*
X38086D01*
X55086Y62500D01*
X56000D01*
X547854Y62440D01*
X591000Y105586D01*
Y142086D01*
X609500Y160586D01*
Y195414D01*
X605914Y199000D01*
X566086D01*
X554585Y187500D01*
X486893Y187440D01*
X417915Y187500D01*
X410914Y194500D01*
X-33307Y194440D01*
Y287047D01*
X-1378D01*
G03Y299803I0J6378D01*
G01X-33307D01*
Y362941D01*
X-3937D01*
G03X3004Y369882I0J6941D01*
G01Y468504D01*
G37*
G36*
G01X-1866Y115906D02*
X-33307D01*
Y192440D01*
X410086Y192500D01*
X417085Y185500D01*
X486893Y185440D01*
X555415Y185500D01*
X566914Y197000D01*
X605086D01*
X607500Y194586D01*
Y161414D01*
X589000Y142914D01*
Y106414D01*
X547026Y64440D01*
X56000Y64500D01*
X55914D01*
X38914Y81500D01*
X5000D01*
Y106969D01*
G03X-1538Y115578I-8937J0D01*
G01X-1866Y115906D01*
G37*
%LPD*%
G75*
G36*
G01X25118Y253002D02*
G02X32056Y246063I0J-6938D01*
G01Y226378D01*
G02X25118Y219440I-6938J0D01*
G01X21181D01*
G02X14242Y226378I0J6939D01*
G01Y246063D01*
G02X21181Y253002I6939J0D01*
G01X25118D01*
G37*
G54D24*
X600709Y136909D03*
Y311909D03*
G54D19*
X559489Y427559D03*
X603780Y442126D03*
G54D17*
X570709Y161889D03*
X580709D03*
X570709Y191889D03*
X580709D03*
X570709Y181889D03*
X580709D03*
X570709Y171889D03*
X580709D03*
X570709Y276929D03*
X580709D03*
X570709Y266929D03*
X580709D03*
X570709Y256929D03*
X580709D03*
X570709Y286929D03*
X580709D03*
X590709Y161889D03*
X600709D03*
Y214409D03*
X590709Y204409D03*
Y191889D03*
X600709D03*
X590709Y181889D03*
X600709D03*
X590709Y171889D03*
X600709D03*
X590709Y244409D03*
Y276929D03*
X600709D03*
X590709Y266929D03*
X600709D03*
X590709Y256929D03*
X600709D03*
Y234409D03*
X590709Y224409D03*
Y286929D03*
X600709D03*
G54D16*
X498661Y23622D03*
X518346Y448818D03*
G54D13*
X3398Y326936D03*
X2334Y318654D03*
X1494Y343705D03*
X5694D03*
X10000Y332000D03*
X30923Y335665D03*
X26723D03*
X57398Y348682D03*
X52705Y348626D03*
X48325Y348514D03*
X37500Y386500D03*
X60052Y394674D03*
X55352D03*
X51094Y394478D03*
X520500Y331000D03*
X489500Y375500D03*
X485500D03*
X561500Y232000D03*
X557000Y231500D03*
X543900Y314000D03*
X600000Y337500D03*
Y342000D03*
X595500D03*
Y337500D03*
X612798Y413000D03*
X617798D03*
G54D20*
X571496Y433071D03*
X581339D03*
X591182D03*
G54D18*
X570709Y214409D03*
X580709D03*
X570709Y204409D03*
X580709D03*
X570709Y244409D03*
X580709D03*
X570709Y234409D03*
X580709D03*
X570709Y224409D03*
X580709D03*
X590709Y214409D03*
X600709Y204409D03*
Y244409D03*
X590709Y234409D03*
X600709Y224409D03*
G54D15*
X22000Y387500D03*
X55500Y417000D03*
X512500Y323000D03*
X492000Y321000D03*
X506500Y305500D03*
X520381Y300757D03*
X537136Y326402D03*
X525161Y311000D03*
G54D14*
X25500Y353000D03*
X25000Y343000D03*
X33986Y362933D03*
X22000Y374500D03*
X61898Y358936D03*
X546600Y257971D03*
G54D10*
X-23621Y15748D03*
Y937008D03*
X1312285Y15747D03*
X1312281Y889328D03*
G54D21*
X600709Y136909D03*
Y311909D03*
G54D12*
X6419Y116482D03*
X-3350Y117504D03*
X6419Y126482D03*
X-3581D03*
X6419Y136482D03*
X-3581D03*
X6419Y146482D03*
X-3581D03*
X6419Y156482D03*
X-3581D03*
X-2602Y206936D03*
X7398D03*
X-2602Y216936D03*
X7398D03*
X6419Y166482D03*
X-3581D03*
Y176482D03*
X6419D03*
X-2602Y226936D03*
X7398D03*
X-2602Y246936D03*
X7398D03*
X-2602Y236936D03*
X7398D03*
Y256936D03*
X-2602D03*
Y266936D03*
X7398D03*
Y276936D03*
X-2602D03*
X7398Y286936D03*
X-2948Y302202D03*
X-2602Y316436D03*
X-7102Y327202D03*
X-6940Y316247D03*
X-6602Y347202D03*
X-7102Y337202D03*
X-6602Y357202D03*
X6898Y387436D03*
X6398Y369936D03*
X6898Y445436D03*
Y465436D03*
X16419Y6482D03*
Y26482D03*
X36419Y6482D03*
Y26482D03*
X56419Y46482D03*
X16419Y86482D03*
X36419D03*
X56419Y66482D03*
Y86482D03*
X26419Y116482D03*
X16419D03*
X26419Y126482D03*
X16419D03*
X26419Y136482D03*
X16419D03*
X26419Y146482D03*
X16419D03*
X26419Y156482D03*
X16419D03*
X36419Y126482D03*
X16419Y106482D03*
X36419D03*
Y146482D03*
X56419Y126482D03*
Y106482D03*
Y146482D03*
X27398Y206936D03*
X17398D03*
X27398Y216936D03*
X17398D03*
X26419Y186482D03*
X16419D03*
X26419Y166482D03*
X16419D03*
Y176482D03*
X26419D03*
X36419Y186482D03*
Y166482D03*
X56419Y186482D03*
Y166482D03*
X57398Y206936D03*
X37398D03*
X17398Y256936D03*
X27398D03*
Y266936D03*
X17398D03*
X57398Y226936D03*
X36769D03*
X57398Y246936D03*
Y266936D03*
X36769Y246936D03*
X37398Y266936D03*
X17398Y276936D03*
X27398Y286936D03*
X17398D03*
X27398Y276936D03*
X57398Y286936D03*
X37398D03*
X64398Y304436D03*
X34898Y344936D03*
X62398Y338436D03*
X62000Y442500D03*
X35830Y442464D03*
X19898Y465436D03*
X39898D03*
X76419Y46482D03*
X116419D03*
X96419D03*
X76419Y66482D03*
Y86482D03*
X116419Y66482D03*
X96419D03*
X116419Y86482D03*
X96419D03*
X76419Y126482D03*
Y106482D03*
Y146482D03*
X116419Y126482D03*
Y106482D03*
X96419Y126482D03*
Y106482D03*
X116419Y146482D03*
X96419D03*
X76419Y186482D03*
Y166482D03*
X77398Y206936D03*
X116419Y186482D03*
Y166482D03*
X96419Y186482D03*
Y166482D03*
X117398Y206936D03*
X97398D03*
X77398Y226936D03*
Y246936D03*
Y266936D03*
X117398Y226936D03*
X97398D03*
X117398Y246936D03*
X97398D03*
Y266936D03*
X116398D03*
X77398Y286936D03*
X86398Y303936D03*
X97398Y286936D03*
X116398D03*
X77898Y338436D03*
X78398Y358436D03*
X115330Y337964D03*
X96398Y337936D03*
X115330Y377964D03*
Y357964D03*
X95330Y377964D03*
Y357964D03*
X105330Y442964D03*
X85330D03*
X75500Y417500D03*
X115330Y417964D03*
X95330D03*
X91500Y465500D03*
X117500D03*
X67830Y465464D03*
X136419Y6482D03*
Y46482D03*
X176419Y6482D03*
Y26482D03*
X156419Y6482D03*
Y26482D03*
X176419Y46482D03*
X156419D03*
X136419Y66482D03*
Y86482D03*
X176419Y66482D03*
X156419D03*
X176419Y86482D03*
X156419D03*
X136419Y126482D03*
Y106482D03*
Y146482D03*
X176419Y126482D03*
Y106482D03*
X156419Y126482D03*
Y106482D03*
X176419Y146482D03*
X156419D03*
X136419Y186482D03*
Y166482D03*
X137398Y206936D03*
X176419Y186482D03*
Y166482D03*
X156419Y186482D03*
Y166482D03*
X177398Y206436D03*
X157398Y206936D03*
X137398Y226936D03*
Y246936D03*
Y266936D03*
X177398Y226936D03*
X157398D03*
X177398Y246936D03*
Y266936D03*
X157398Y246936D03*
Y266936D03*
X137398Y286936D03*
X177398D03*
X157398D03*
X135330Y337964D03*
Y377964D03*
Y357964D03*
X175330Y337964D03*
X155330D03*
X175330Y377964D03*
Y357964D03*
X155330Y377964D03*
Y357964D03*
X132000Y442500D03*
X135330Y417964D03*
X175500Y442000D03*
X175330Y417964D03*
X155000Y442000D03*
X155330Y417964D03*
X139898Y465436D03*
X159898D03*
X196419Y6482D03*
Y26482D03*
Y46482D03*
X236419Y6482D03*
Y26482D03*
X216419Y6482D03*
Y26482D03*
X236419Y46482D03*
X216419D03*
X196419Y66482D03*
Y86482D03*
X236419Y66482D03*
X216419D03*
X236419Y86482D03*
X216419D03*
X196419Y126482D03*
Y106482D03*
Y146482D03*
X236419Y126482D03*
Y106482D03*
X216419Y126482D03*
Y106482D03*
X236419Y146482D03*
X216419D03*
X196419Y186482D03*
Y166482D03*
X197398Y206436D03*
X236419Y186482D03*
Y166482D03*
X216419Y186482D03*
Y166482D03*
X217398Y206436D03*
X197398Y226936D03*
Y246936D03*
Y266936D03*
X217398Y226936D03*
Y246936D03*
Y266936D03*
X197398Y286936D03*
X217398D03*
X195330Y337964D03*
Y377964D03*
Y357964D03*
X235330Y337964D03*
X215330D03*
X235330Y377964D03*
Y357964D03*
X215330Y377964D03*
Y357964D03*
X196000Y442500D03*
X195330Y417964D03*
X235830Y442464D03*
X235330Y417964D03*
X215830Y442464D03*
X215330Y417964D03*
X179898Y465436D03*
X219898D03*
X199898D03*
X256419Y6482D03*
Y26482D03*
X276419Y6482D03*
Y26482D03*
X256419Y46482D03*
X276419D03*
X256419Y66482D03*
X273500Y66500D03*
X256419Y86482D03*
X274500Y86500D03*
X256419Y126482D03*
X276419D03*
X256419Y106482D03*
X274500Y106500D03*
X256419Y146482D03*
X276419D03*
X237398Y206436D03*
X256419Y186482D03*
X275500Y186500D03*
X251500Y166500D03*
X276419Y166482D03*
X257398Y206436D03*
X277398D03*
X237398Y226936D03*
Y246936D03*
Y266936D03*
X257398Y226936D03*
X277398D03*
X257398Y246936D03*
X277398D03*
X257398Y266936D03*
X277398D03*
X237398Y286936D03*
X257398D03*
X279398D03*
X255330Y337964D03*
X275330D03*
X255330Y377964D03*
X275330D03*
X255330Y357964D03*
X275330D03*
X255830Y442464D03*
X275830D03*
X255330Y417964D03*
X275330D03*
X239898Y465436D03*
X279898D03*
X259898D03*
X296419Y6482D03*
Y26482D03*
Y46482D03*
X316419Y6482D03*
Y26482D03*
X336419Y6482D03*
Y26482D03*
X316419Y46482D03*
X336419D03*
X302000Y67000D03*
X301000Y86500D03*
X316419Y66482D03*
X336419D03*
X316419Y86482D03*
X336419D03*
X296419Y126482D03*
X300000Y106500D03*
X296419Y146482D03*
X316419Y126482D03*
X336419D03*
X316419Y106482D03*
X336419D03*
X316419Y146482D03*
X336419D03*
X296419Y186482D03*
X295500Y169000D03*
X297398Y206436D03*
X317500Y186500D03*
X336419Y186482D03*
X317000Y166500D03*
X338500Y166000D03*
X317398Y206436D03*
X337398D03*
X297398Y226936D03*
Y246936D03*
Y266936D03*
X317398Y226936D03*
X337398D03*
X317398Y246936D03*
X337398D03*
X317398Y266936D03*
X337398D03*
X300398Y286936D03*
X317398D03*
X337398D03*
X295330Y337964D03*
Y377964D03*
Y357964D03*
X315330Y337964D03*
X335330D03*
X315330Y377964D03*
X335330D03*
X315330Y357964D03*
X335330D03*
X295830Y442464D03*
X295330Y417964D03*
X315830Y442464D03*
X335830D03*
X315330Y417964D03*
X335330D03*
X299898Y465436D03*
X339898D03*
X319898D03*
X356419Y6482D03*
Y26482D03*
Y46482D03*
X376419Y6482D03*
Y26482D03*
X396419Y6482D03*
Y26482D03*
X376419Y46482D03*
X396419D03*
X356419Y66482D03*
Y86482D03*
X376419Y66482D03*
X396419D03*
X376419Y86482D03*
X396419D03*
X356419Y126482D03*
Y106482D03*
Y146482D03*
X376419Y126482D03*
X396419D03*
X376419Y106482D03*
X396419D03*
X376419Y146482D03*
X396419D03*
X357500Y186500D03*
X354500Y166500D03*
X357398Y206436D03*
X376419Y186482D03*
X396419D03*
X380000Y166500D03*
X396419Y166482D03*
X377398Y206436D03*
X397398D03*
X357398Y226936D03*
Y246936D03*
Y266936D03*
X377398Y226936D03*
X397398D03*
X377398Y246936D03*
X397398D03*
X377398Y266936D03*
X397398D03*
X357398Y286936D03*
X377398D03*
X397398D03*
X355330Y337964D03*
Y377964D03*
Y357964D03*
X375330Y337964D03*
X395330D03*
X375330Y377964D03*
X395330D03*
X375330Y357964D03*
X395330D03*
X355830Y442464D03*
X355330Y417964D03*
X375830Y442464D03*
X395830D03*
X375330Y417964D03*
X395330D03*
X399898Y465436D03*
X379898D03*
X359898D03*
X416419Y6482D03*
Y26482D03*
X436419Y6482D03*
X416419Y46482D03*
X436419D03*
X456419D03*
X416419Y66482D03*
X436419D03*
X456419D03*
X416419Y86482D03*
X436419D03*
X456419D03*
X416419Y126482D03*
X436419D03*
X456419D03*
X416419Y106482D03*
X436419D03*
X456419D03*
X416419Y146482D03*
X436419D03*
X456419D03*
X416500Y166000D03*
X417519Y174482D03*
Y170282D03*
X425919D03*
X421719D03*
Y174482D03*
X431100Y174500D03*
Y170300D03*
X439500D03*
Y174500D03*
X435300Y170300D03*
Y174500D03*
X444100D03*
Y170300D03*
X452500D03*
Y174500D03*
X448300Y170300D03*
Y174500D03*
X457100Y175000D03*
Y170800D03*
X461300D03*
Y175000D03*
X418300Y197500D03*
Y201700D03*
X422500D03*
X426700D03*
X422500Y197500D03*
X426700D03*
X431300D03*
Y201700D03*
X435500D03*
X439700D03*
X435500Y197500D03*
X439700D03*
X444800D03*
Y201700D03*
X449000D03*
X453200D03*
X449000Y197500D03*
X453200D03*
X457800D03*
Y201700D03*
X462000D03*
Y197500D03*
X425919Y174482D03*
X436500Y166000D03*
X456500Y166500D03*
X417398Y206436D03*
X437398D03*
X457398D03*
X417398Y226936D03*
X437398D03*
X457398D03*
X417398Y246936D03*
X437398D03*
X457398D03*
X437398Y266936D03*
X457398D03*
X418398D03*
X437398Y286936D03*
X457398D03*
X418398D03*
X415330Y337964D03*
X435398Y338436D03*
X455398D03*
X415330Y377964D03*
Y357964D03*
X435398Y358436D03*
Y378436D03*
X455398Y358436D03*
Y378436D03*
X435830Y442464D03*
X435330Y417964D03*
X455330D03*
X415830Y442464D03*
X415330Y417964D03*
X454500Y465500D03*
X439898Y465436D03*
X419898D03*
X516419Y6482D03*
X476419Y46482D03*
X496419D03*
X516419D03*
Y66482D03*
X476419D03*
X496419D03*
X516419Y86482D03*
X496419D03*
X476419D03*
Y126482D03*
X516419D03*
X496419D03*
X516419Y106482D03*
X496419D03*
X476419D03*
X485443Y160670D03*
X481243D03*
X493843D03*
X489643D03*
X476419Y146482D03*
X516419D03*
X496419D03*
X519221Y160912D03*
X510821D03*
X506621D03*
X515021D03*
X465500Y170800D03*
Y175000D03*
X466200Y201700D03*
Y197500D03*
X485443Y164870D03*
X481243D03*
X493843D03*
X489643D03*
X477284Y174586D03*
X473084D03*
Y170386D03*
X477284D03*
X498395Y174685D03*
Y170485D03*
X492911Y206602D03*
X488711D03*
X492911Y210802D03*
X488711D03*
X484511D03*
Y206602D03*
X480311Y210802D03*
Y206602D03*
X498052Y200389D03*
Y196189D03*
X477087Y201172D03*
X472887D03*
X477087Y196972D03*
X472887D03*
X519221Y165112D03*
X510821D03*
X506621D03*
X515021D03*
X502595Y174685D03*
Y170485D03*
X506135Y210557D03*
X510335D03*
X514535D03*
X518735D03*
X506135Y206357D03*
X510335D03*
X514535D03*
X518735D03*
X502252Y200389D03*
Y196189D03*
X497398Y226936D03*
X477398D03*
X520898Y228436D03*
X497398Y246936D03*
X477398D03*
Y266936D03*
X495398Y338436D03*
X475398D03*
X495398Y358436D03*
Y378436D03*
X475398Y358436D03*
Y378436D03*
X477000Y418000D03*
X499000Y418500D03*
X466500Y428000D03*
X533619Y6482D03*
Y26482D03*
Y46482D03*
X550819Y6482D03*
Y26482D03*
Y46482D03*
X568019Y6482D03*
Y26482D03*
Y46482D03*
X573623Y66967D03*
X536419Y66482D03*
X556419D03*
X536419Y86482D03*
X556419D03*
X576419Y106482D03*
Y126482D03*
X536419D03*
X556419D03*
X536419Y106482D03*
X556419D03*
X544476Y161322D03*
X531876D03*
X536076D03*
X540276D03*
X536419Y146482D03*
X556419D03*
X544477Y210389D03*
X544476Y165522D03*
X536076D03*
X531876D03*
X540276D03*
X552924Y175124D03*
X548724D03*
Y170924D03*
X552924D03*
X527711Y175174D03*
X523511D03*
Y170974D03*
X527711D03*
X531877Y210389D03*
X536077D03*
X540277D03*
X531877Y206189D03*
X536077D03*
X540277D03*
X544477D03*
X527761Y200632D03*
X523561D03*
X527761Y196432D03*
X523561D03*
X553171Y200877D03*
X548971D03*
X553171Y196677D03*
X548971D03*
X540898Y228436D03*
X560500Y268000D03*
X549500Y305500D03*
X559996Y282972D03*
X561500Y298000D03*
X534000Y282000D03*
X577500Y305000D03*
X548000Y442500D03*
X553000Y425000D03*
X568500Y464841D03*
X538000D03*
X634119Y26482D03*
X585219Y46482D03*
Y26482D03*
Y6482D03*
X602419Y26482D03*
Y6482D03*
X619619D03*
Y26482D03*
Y46482D03*
X634119D03*
Y6482D03*
X602419Y46482D03*
X628500Y104000D03*
X626500Y78500D03*
X611253Y65701D03*
X584543Y86671D03*
X611398Y86936D03*
X633753Y65701D03*
X633898Y86936D03*
X634000Y123500D03*
X607000D03*
X616000Y138000D03*
Y115500D03*
X594500Y117000D03*
X616000Y173500D03*
X615500Y199000D03*
X615898Y244436D03*
Y224436D03*
X615398Y266436D03*
X587500Y318500D03*
X600000Y298500D03*
X616498Y316236D03*
X615398Y284436D03*
X633398Y325436D03*
X630000Y345500D03*
Y387500D03*
X610898Y425436D03*
Y445436D03*
X632898Y404936D03*
Y444936D03*
Y424936D03*
X592000Y464841D03*
X610898Y465436D03*
X632898Y464936D03*
G54D11*
X30157Y61023D03*
Y415354D03*
%LPC*%
G75*
G54D22*
G01X-4246Y-109426D02*
Y-189426D01*
G01D02*
X1290354D01*
G01X-4246Y-144926D02*
X1290354D01*
G01X-8246Y-93426D02*
G02I-12000J0D01*
G01X-13396D02*
G02I-6850J0D01*
G01X-20246Y-109426D02*
Y-77426D01*
G01X-4246Y-93426D02*
X-36246D01*
G01X-4246Y-109426D02*
X1290354D01*
G01X502854D02*
Y-189426D01*
G01X640354Y-109426D02*
Y-189426D01*
G01X755354Y-109426D02*
Y-189426D01*
G01X922854Y-109426D02*
Y-189426D01*
G01X1092854Y-109426D02*
Y-189426D01*
G01X1290354Y-109426D02*
Y-189426D01*
G01X1318354Y-93426D02*
G02I-12000J0D01*
G01X1313204D02*
G02I-6850J0D01*
G01X1306354Y-109426D02*
Y-77426D01*
G01X1322354Y-93426D02*
X1290354D01*
G54D23*
G01X121969Y-179426D02*
Y-161926D01*
G01X131139D02*
Y-179426D01*
G01Y-170676D02*
X121969D01*
G01X144054Y-179426D02*
X142744Y-179134D01*
X141434Y-177968D01*
X140560Y-175926D01*
X140124Y-173593D01*
X140560Y-171259D01*
X141434Y-169218D01*
X142744Y-168051D01*
X144054Y-167760D01*
X145364Y-168051D01*
X146674Y-169218D01*
X147547Y-171259D01*
X147766Y-173593D01*
X147547Y-175926D01*
X146674Y-177968D01*
X145364Y-179134D01*
X144054Y-179426D01*
G01X157842D02*
Y-167760D01*
G01Y-170676D02*
X158716Y-169218D01*
X160026Y-168051D01*
X161772Y-167760D01*
X163300Y-168051D01*
X164611Y-169218D01*
X165266Y-171259D01*
Y-179426D01*
G01X175779Y-171551D02*
X182766D01*
X182111Y-169509D01*
X181019Y-168343D01*
X179491Y-167760D01*
X177962Y-168051D01*
X176652Y-168926D01*
X175779Y-170968D01*
X175342Y-172718D01*
Y-174468D01*
X175779Y-176218D01*
X176871Y-177968D01*
X178181Y-179134D01*
X179709Y-179426D01*
X181237Y-178843D01*
X182766Y-177093D01*
G01X191969Y-184676D02*
X193279Y-185259D01*
X195026Y-184676D01*
X196117Y-183510D01*
X196991Y-182051D01*
X198300Y-177385D01*
X201139Y-167760D01*
G01X194152D02*
X198300Y-177385D01*
G01X233300Y-170093D02*
X234174Y-169218D01*
X234829Y-167760D01*
X235266Y-165717D01*
X234829Y-163968D01*
X233956Y-162801D01*
X232427Y-161926D01*
X226532D01*
Y-179426D01*
X233737D01*
X235266Y-178260D01*
X236139Y-176509D01*
X236576Y-174468D01*
X236139Y-172426D01*
X234829Y-170676D01*
X233300Y-170093D01*
X226532D01*
G01X252984Y-179426D02*
Y-167760D01*
G01Y-169801D02*
X252111Y-168635D01*
X250800Y-168051D01*
X249272Y-167760D01*
X247744Y-168343D01*
X246434Y-169509D01*
X245560Y-171259D01*
X245124Y-173593D01*
X245560Y-175926D01*
X246434Y-177676D01*
X247744Y-178843D01*
X249272Y-179426D01*
X250800Y-179134D01*
X252111Y-178260D01*
X252984Y-177093D01*
G01X270484Y-161926D02*
Y-179426D01*
G01Y-176802D02*
X269611Y-178260D01*
X268300Y-179134D01*
X266772Y-179426D01*
X265026Y-178843D01*
X263716Y-177385D01*
X262842Y-175635D01*
X262624Y-173593D01*
X262842Y-171551D01*
X263716Y-169801D01*
X265026Y-168343D01*
X266772Y-167760D01*
X268300Y-168051D01*
X269392Y-168635D01*
X270484Y-169801D01*
G01X280997Y-183801D02*
X282526Y-184968D01*
X284272Y-185259D01*
X285800Y-184968D01*
X287111Y-183510D01*
X287984Y-181468D01*
Y-167760D01*
G01Y-170093D02*
X287111Y-168926D01*
X285800Y-168051D01*
X284272Y-167760D01*
X282526Y-168343D01*
X281434Y-169509D01*
X280560Y-171551D01*
X280124Y-173593D01*
X280342Y-175343D01*
X281216Y-177385D01*
X282526Y-178843D01*
X284272Y-179426D01*
X285582Y-179134D01*
X287111Y-177968D01*
X287984Y-176802D01*
G01X298279Y-171551D02*
X305266D01*
X304611Y-169509D01*
X303519Y-168343D01*
X301991Y-167760D01*
X300462Y-168051D01*
X299152Y-168926D01*
X298279Y-170968D01*
X297842Y-172718D01*
Y-174468D01*
X298279Y-176218D01*
X299371Y-177968D01*
X300681Y-179134D01*
X302209Y-179426D01*
X303737Y-178843D01*
X305266Y-177093D01*
G01X315997Y-179426D02*
Y-167760D01*
G01Y-170093D02*
X317089Y-168926D01*
X318181Y-168051D01*
X319709Y-167760D01*
X320800Y-168051D01*
X322111Y-168926D01*
G01X349687Y-179426D02*
Y-161926D01*
X354927D01*
X356674Y-162801D01*
X357984Y-164843D01*
X358421Y-167176D01*
X357984Y-169509D01*
X356892Y-171259D01*
X354927Y-172135D01*
X349687D01*
G01X371554Y-161926D02*
Y-179426D01*
G01X366532Y-161926D02*
X376576D01*
G01X390800Y-170093D02*
X391674Y-169218D01*
X392329Y-167760D01*
X392766Y-165717D01*
X392329Y-163968D01*
X391456Y-162801D01*
X389927Y-161926D01*
X384032D01*
Y-179426D01*
X391237D01*
X392766Y-178260D01*
X393639Y-176509D01*
X394076Y-174468D01*
X393639Y-172426D01*
X392329Y-170676D01*
X390800Y-170093D01*
X384032D01*
G01X208377Y-134426D02*
Y-116926D01*
X214054Y-131509D01*
X219731Y-116926D01*
Y-134426D01*
G01X231554D02*
X230244Y-134134D01*
X228934Y-132968D01*
X228060Y-130926D01*
X227624Y-128593D01*
X228060Y-126259D01*
X228934Y-124218D01*
X230244Y-123051D01*
X231554Y-122760D01*
X232864Y-123051D01*
X234174Y-124218D01*
X235047Y-126259D01*
X235266Y-128593D01*
X235047Y-130926D01*
X234174Y-132968D01*
X232864Y-134134D01*
X231554Y-134426D01*
G01X252984Y-116926D02*
Y-134426D01*
G01Y-131802D02*
X252111Y-133260D01*
X250800Y-134134D01*
X249272Y-134426D01*
X247526Y-133843D01*
X246216Y-132385D01*
X245342Y-130635D01*
X245124Y-128593D01*
X245342Y-126551D01*
X246216Y-124801D01*
X247526Y-123343D01*
X249272Y-122760D01*
X250800Y-123051D01*
X251892Y-123635D01*
X252984Y-124801D01*
G01X263279Y-126551D02*
X270266D01*
X269611Y-124509D01*
X268519Y-123343D01*
X266991Y-122760D01*
X265462Y-123051D01*
X264152Y-123926D01*
X263279Y-125968D01*
X262842Y-127718D01*
Y-129468D01*
X263279Y-131218D01*
X264371Y-132968D01*
X265681Y-134134D01*
X267209Y-134426D01*
X268737Y-133843D01*
X270266Y-132093D01*
G01X284054Y-134426D02*
Y-116926D01*
G01X536554Y-179426D02*
Y-161926D01*
X533934Y-165426D01*
G01Y-179426D02*
X539174D01*
G01X556674D02*
Y-161926D01*
X548595Y-174468D01*
X559513D01*
G01X567406Y-172135D02*
X568934Y-170093D01*
X570244Y-168926D01*
X571991Y-168343D01*
X573519Y-168926D01*
X574611Y-170093D01*
X575484Y-171843D01*
X575702Y-173884D01*
X575484Y-175635D01*
X574611Y-177385D01*
X573300Y-178843D01*
X571772Y-179426D01*
X570026Y-178843D01*
X568497Y-177093D01*
X567624Y-174468D01*
X567406Y-171551D01*
X567842Y-167760D01*
X568497Y-165717D01*
X569589Y-163676D01*
X571117Y-162218D01*
X572646Y-161926D01*
X574174Y-162509D01*
X575266Y-163968D01*
G01X584906Y-164843D02*
X586216Y-163093D01*
X587744Y-162218D01*
X589491Y-161926D01*
X591674Y-162509D01*
X593202Y-163968D01*
X593639Y-165717D01*
X593421Y-167468D01*
X592547Y-168926D01*
X588181Y-171843D01*
X586216Y-173884D01*
X584906Y-176802D01*
X584469Y-179426D01*
X593639D01*
G01X602842Y-177385D02*
X604371Y-178843D01*
X606117Y-179426D01*
X607864Y-178843D01*
X609392Y-177093D01*
X610484Y-174468D01*
X610921Y-171843D01*
Y-168635D01*
X610484Y-166010D01*
X609392Y-163676D01*
X608082Y-162509D01*
X606554Y-161926D01*
X604807Y-162509D01*
X603497Y-163676D01*
X602624Y-165426D01*
X602187Y-167760D01*
X602624Y-169801D01*
X603716Y-171843D01*
X605026Y-173010D01*
X606554Y-173301D01*
X608300Y-172718D01*
X609611Y-171259D01*
X610921Y-168635D01*
G01X523437Y-134426D02*
Y-116926D01*
X528677D01*
X530424Y-117801D01*
X531734Y-119843D01*
X532171Y-122176D01*
X531734Y-124509D01*
X530642Y-126259D01*
X528677Y-127135D01*
X523437D01*
G01X550107Y-118385D02*
X548797Y-117509D01*
X547269Y-116926D01*
X545522D01*
X543557Y-117801D01*
X542029Y-119259D01*
X540937Y-121010D01*
X540064Y-123926D01*
X539845Y-126551D01*
X540282Y-129176D01*
X540937Y-130926D01*
X542247Y-132676D01*
X543776Y-133843D01*
X545304Y-134426D01*
X546832D01*
X548361Y-133843D01*
X549671Y-132968D01*
X550763Y-131802D01*
G01X564550Y-125093D02*
X565424Y-124218D01*
X566079Y-122760D01*
X566516Y-120717D01*
X566079Y-118968D01*
X565206Y-117801D01*
X563677Y-116926D01*
X557782D01*
Y-134426D01*
X564987D01*
X566516Y-133260D01*
X567389Y-131509D01*
X567826Y-129468D01*
X567389Y-127426D01*
X566079Y-125676D01*
X564550Y-125093D01*
X557782D01*
G01X573754Y-140259D02*
X586854D01*
G01X592782Y-134426D02*
Y-116926D01*
X602826Y-134426D01*
Y-116926D01*
G01X615304Y-134426D02*
X613557Y-134134D01*
X612029Y-132968D01*
X610719Y-131218D01*
X609845Y-129176D01*
X609409Y-126843D01*
Y-124509D01*
X609845Y-122176D01*
X610719Y-120134D01*
X612029Y-118385D01*
X613557Y-117218D01*
X615304Y-116926D01*
X617050Y-117218D01*
X618579Y-118385D01*
X619889Y-120134D01*
X620763Y-122176D01*
X621199Y-124509D01*
Y-126843D01*
X620763Y-129176D01*
X619889Y-131218D01*
X618579Y-132968D01*
X617050Y-134134D01*
X615304Y-134426D01*
G01X689104Y-179426D02*
Y-161926D01*
X686484Y-165426D01*
G01Y-179426D02*
X691724D01*
G01X701145D02*
X706604Y-161926D01*
X712063Y-179426D01*
G01X710097Y-173301D02*
X703110D01*
G01X666145Y-116926D02*
X671604Y-134426D01*
X677063Y-116926D01*
G01X693471Y-134426D02*
X684737D01*
Y-116926D01*
X693471D01*
G01X689977Y-125384D02*
X684737D01*
G01X702237Y-134426D02*
Y-116926D01*
X707696D01*
X709442Y-117801D01*
X710534Y-118968D01*
X710971Y-121301D01*
X710534Y-123635D01*
X709224Y-125093D01*
X707696Y-125968D01*
X702237D01*
G01X707696D02*
X710971Y-134426D01*
G01X724104Y-135009D02*
X723667Y-134718D01*
Y-134134D01*
X724104Y-133843D01*
X724541Y-134134D01*
Y-134718D01*
X724104Y-135009D01*
G01X878421Y-161926D02*
Y-179426D01*
X869687D01*
G01X861357Y-175926D02*
X860048Y-177968D01*
X858301Y-179134D01*
X856336Y-179426D01*
X854589Y-179134D01*
X852842Y-177676D01*
X851751Y-175926D01*
X851532Y-174176D01*
X851969Y-172135D01*
X853497Y-170676D01*
X855026Y-170093D01*
X856991D01*
G01X855026D02*
X853716Y-169218D01*
X852624Y-167760D01*
X852187Y-166010D01*
X852624Y-164259D01*
X853716Y-162801D01*
X855681Y-161926D01*
X857646Y-162218D01*
X859611Y-163385D01*
G01X844513Y-161926D02*
X839054Y-179426D01*
X833595Y-161926D01*
G01X816751Y-163385D02*
X818061Y-162509D01*
X819589Y-161926D01*
X821336D01*
X823301Y-162801D01*
X824829Y-164259D01*
X825921Y-166010D01*
X826794Y-168926D01*
X827013Y-171551D01*
X826576Y-174176D01*
X825921Y-175926D01*
X824611Y-177676D01*
X823082Y-178843D01*
X821554Y-179426D01*
X820026D01*
X818497Y-178843D01*
X817187Y-177968D01*
X816095Y-176802D01*
G01X799251Y-163385D02*
X800561Y-162509D01*
X802089Y-161926D01*
X803836D01*
X805801Y-162801D01*
X807329Y-164259D01*
X808421Y-166010D01*
X809294Y-168926D01*
X809513Y-171551D01*
X809076Y-174176D01*
X808421Y-175926D01*
X807111Y-177676D01*
X805582Y-178843D01*
X804054Y-179426D01*
X802526D01*
X800997Y-178843D01*
X799687Y-177968D01*
X798595Y-176802D01*
G01X790937Y-116926D02*
Y-134426D01*
X799671D01*
G01X816734D02*
Y-122760D01*
G01Y-124801D02*
X815861Y-123635D01*
X814550Y-123051D01*
X813022Y-122760D01*
X811494Y-123343D01*
X810184Y-124509D01*
X809310Y-126259D01*
X808874Y-128593D01*
X809310Y-130926D01*
X810184Y-132676D01*
X811494Y-133843D01*
X813022Y-134426D01*
X814550Y-134134D01*
X815861Y-133260D01*
X816734Y-132093D01*
G01X825719Y-139676D02*
X827029Y-140259D01*
X828776Y-139676D01*
X829867Y-138510D01*
X830741Y-137051D01*
X832050Y-132385D01*
X834889Y-122760D01*
G01X827902D02*
X832050Y-132385D01*
G01X844529Y-126551D02*
X851516D01*
X850861Y-124509D01*
X849769Y-123343D01*
X848241Y-122760D01*
X846712Y-123051D01*
X845402Y-123926D01*
X844529Y-125968D01*
X844092Y-127718D01*
Y-129468D01*
X844529Y-131218D01*
X845621Y-132968D01*
X846931Y-134134D01*
X848459Y-134426D01*
X849987Y-133843D01*
X851516Y-132093D01*
G01X862247Y-134426D02*
Y-122760D01*
G01Y-125093D02*
X863339Y-123926D01*
X864431Y-123051D01*
X865959Y-122760D01*
X867050Y-123051D01*
X868361Y-123926D01*
G01X879529Y-132385D02*
X880621Y-133551D01*
X882149Y-134426D01*
X883459D01*
X884769Y-133843D01*
X885642Y-132968D01*
X886079Y-131802D01*
X885861Y-130051D01*
X884987Y-129176D01*
X881057Y-127426D01*
X880184Y-125384D01*
X880621Y-123926D01*
X881494Y-123051D01*
X882804Y-122760D01*
X884114Y-123051D01*
X885424Y-123926D01*
G01X924737Y-175926D02*
X925829Y-177676D01*
X927139Y-178843D01*
X928667Y-179426D01*
X930414Y-178843D01*
X931724Y-177676D01*
X933034Y-175926D01*
X933471Y-173593D01*
Y-161926D01*
G01X946604Y-179426D02*
X944857Y-179134D01*
X943329Y-177968D01*
X942019Y-176218D01*
X941145Y-174176D01*
X940709Y-171843D01*
Y-169509D01*
X941145Y-167176D01*
X942019Y-165134D01*
X943329Y-163385D01*
X944857Y-162218D01*
X946604Y-161926D01*
X948350Y-162218D01*
X949879Y-163385D01*
X951189Y-165134D01*
X952063Y-167176D01*
X952499Y-169509D01*
Y-171843D01*
X952063Y-174176D01*
X951189Y-176218D01*
X949879Y-177968D01*
X948350Y-179134D01*
X946604Y-179426D01*
G01X959519Y-177093D02*
X961266Y-178551D01*
X963231Y-179426D01*
X964977D01*
X966724Y-178551D01*
X968034Y-177093D01*
X968689Y-175051D01*
X968252Y-173010D01*
X967161Y-171259D01*
X965196Y-170093D01*
X962576Y-169509D01*
X961047Y-168343D01*
X960392Y-166301D01*
X960829Y-164259D01*
X961921Y-162801D01*
X963449Y-161926D01*
X964977D01*
X966506Y-162509D01*
X967816Y-163968D01*
G01X985971Y-179426D02*
X977237D01*
Y-161926D01*
X985971D01*
G01X982477Y-170384D02*
X977237D01*
G01X994737Y-179426D02*
Y-161926D01*
X999977D01*
X1001724Y-162801D01*
X1003034Y-164843D01*
X1003471Y-167176D01*
X1003034Y-169509D01*
X1001942Y-171259D01*
X999977Y-172135D01*
X994737D01*
G01X1012019Y-179426D02*
Y-161926D01*
G01X1021189D02*
Y-179426D01*
G01Y-170676D02*
X1012019D01*
G01X1047237Y-161926D02*
Y-179426D01*
X1055971D01*
G01X1063645D02*
X1069104Y-161926D01*
X1074563Y-179426D01*
G01X1072597Y-173301D02*
X1065610D01*
G01X1081801Y-161926D02*
Y-174468D01*
X1082674Y-177093D01*
X1084421Y-178843D01*
X1086604Y-179426D01*
X1088787Y-178843D01*
X1090534Y-177093D01*
X1091407Y-174468D01*
Y-161926D01*
G01X941801Y-134426D02*
Y-116926D01*
X946167D01*
X947914Y-117801D01*
X949224Y-118968D01*
X950316Y-120717D01*
X951189Y-122760D01*
X951407Y-125676D01*
X951189Y-128593D01*
X950316Y-130635D01*
X949224Y-132385D01*
X947914Y-133551D01*
X946167Y-134426D01*
X941801D01*
G01X960829Y-126551D02*
X967816D01*
X967161Y-124509D01*
X966069Y-123343D01*
X964541Y-122760D01*
X963012Y-123051D01*
X961702Y-123926D01*
X960829Y-125968D01*
X960392Y-127718D01*
Y-129468D01*
X960829Y-131218D01*
X961921Y-132968D01*
X963231Y-134134D01*
X964759Y-134426D01*
X966287Y-133843D01*
X967816Y-132093D01*
G01X978329Y-132385D02*
X979421Y-133551D01*
X980949Y-134426D01*
X982259D01*
X983569Y-133843D01*
X984442Y-132968D01*
X984879Y-131802D01*
X984661Y-130051D01*
X983787Y-129176D01*
X979857Y-127426D01*
X978984Y-125384D01*
X979421Y-123926D01*
X980294Y-123051D01*
X981604Y-122760D01*
X982914Y-123051D01*
X984224Y-123926D01*
G01X999104Y-122760D02*
Y-134426D01*
G01Y-118093D02*
X998667Y-117801D01*
Y-117218D01*
X999104Y-116926D01*
X999541Y-117218D01*
Y-117801D01*
X999104Y-118093D01*
G01X1013547Y-138801D02*
X1015076Y-139968D01*
X1016822Y-140259D01*
X1018350Y-139968D01*
X1019661Y-138510D01*
X1020534Y-136468D01*
Y-122760D01*
G01Y-125093D02*
X1019661Y-123926D01*
X1018350Y-123051D01*
X1016822Y-122760D01*
X1015076Y-123343D01*
X1013984Y-124509D01*
X1013110Y-126551D01*
X1012674Y-128593D01*
X1012892Y-130343D01*
X1013766Y-132385D01*
X1015076Y-133843D01*
X1016822Y-134426D01*
X1018132Y-134134D01*
X1019661Y-132968D01*
X1020534Y-131802D01*
G01X1030392Y-134426D02*
Y-122760D01*
G01Y-125676D02*
X1031266Y-124218D01*
X1032576Y-123051D01*
X1034322Y-122760D01*
X1035850Y-123051D01*
X1037161Y-124218D01*
X1037816Y-126259D01*
Y-134426D01*
G01X1048329Y-126551D02*
X1055316D01*
X1054661Y-124509D01*
X1053569Y-123343D01*
X1052041Y-122760D01*
X1050512Y-123051D01*
X1049202Y-123926D01*
X1048329Y-125968D01*
X1047892Y-127718D01*
Y-129468D01*
X1048329Y-131218D01*
X1049421Y-132968D01*
X1050731Y-134134D01*
X1052259Y-134426D01*
X1053787Y-133843D01*
X1055316Y-132093D01*
G01X1066047Y-134426D02*
Y-122760D01*
G01Y-125093D02*
X1067139Y-123926D01*
X1068231Y-123051D01*
X1069759Y-122760D01*
X1070850Y-123051D01*
X1072161Y-123926D01*
G01X1112804Y-179426D02*
Y-161926D01*
X1110184Y-165426D01*
G01Y-179426D02*
X1115424D01*
G01X1130304D02*
Y-161926D01*
X1127684Y-165426D01*
G01Y-179426D02*
X1132924D01*
G01X1143874Y-180009D02*
X1151734Y-161926D01*
G01X1161156Y-164843D02*
X1162466Y-163093D01*
X1163994Y-162218D01*
X1165741Y-161926D01*
X1167924Y-162509D01*
X1169452Y-163968D01*
X1169889Y-165717D01*
X1169671Y-167468D01*
X1168797Y-168926D01*
X1164431Y-171843D01*
X1162466Y-173884D01*
X1161156Y-176802D01*
X1160719Y-179426D01*
X1169889D01*
G01X1178001Y-176802D02*
X1179310Y-178260D01*
X1180839Y-179134D01*
X1182804Y-179426D01*
X1184769Y-178843D01*
X1186297Y-177676D01*
X1187389Y-175635D01*
X1187607Y-173301D01*
X1187171Y-170968D01*
X1186079Y-169509D01*
X1184550Y-168343D01*
X1183022Y-168051D01*
X1181494Y-168343D01*
X1179529Y-169509D01*
X1180184Y-161926D01*
X1186079D01*
G01X1196374Y-180009D02*
X1204234Y-161926D01*
G01X1213656Y-164843D02*
X1214966Y-163093D01*
X1216494Y-162218D01*
X1218241Y-161926D01*
X1220424Y-162509D01*
X1221952Y-163968D01*
X1222389Y-165717D01*
X1222171Y-167468D01*
X1221297Y-168926D01*
X1216931Y-171843D01*
X1214966Y-173884D01*
X1213656Y-176802D01*
X1213219Y-179426D01*
X1222389D01*
G01X1235304Y-161926D02*
X1233557Y-162509D01*
X1232247Y-163968D01*
X1231374Y-165717D01*
X1230719Y-168051D01*
X1230501Y-170676D01*
X1230719Y-173301D01*
X1231374Y-175635D01*
X1232247Y-177385D01*
X1233557Y-178843D01*
X1235304Y-179426D01*
X1237050Y-178843D01*
X1238361Y-177385D01*
X1239234Y-175635D01*
X1239889Y-173301D01*
X1240107Y-170676D01*
X1239889Y-168051D01*
X1239234Y-165717D01*
X1238361Y-163968D01*
X1237050Y-162509D01*
X1235304Y-161926D01*
G01X1252804Y-179426D02*
Y-161926D01*
X1250184Y-165426D01*
G01Y-179426D02*
X1255424D01*
G01X1272924D02*
Y-161926D01*
X1264845Y-174468D01*
X1275763D01*
G01X1160501Y-134426D02*
Y-116926D01*
X1164867D01*
X1166614Y-117801D01*
X1167924Y-118968D01*
X1169016Y-120717D01*
X1169889Y-122760D01*
X1170107Y-125676D01*
X1169889Y-128593D01*
X1169016Y-130635D01*
X1167924Y-132385D01*
X1166614Y-133551D01*
X1164867Y-134426D01*
X1160501D01*
G01X1186734D02*
Y-122760D01*
G01Y-124801D02*
X1185861Y-123635D01*
X1184550Y-123051D01*
X1183022Y-122760D01*
X1181494Y-123343D01*
X1180184Y-124509D01*
X1179310Y-126259D01*
X1178874Y-128593D01*
X1179310Y-130926D01*
X1180184Y-132676D01*
X1181494Y-133843D01*
X1183022Y-134426D01*
X1184550Y-134134D01*
X1185861Y-133260D01*
X1186734Y-132093D01*
G01X1200304Y-116926D02*
Y-134426D01*
G01X1197247Y-122760D02*
X1203361D01*
G01X1214529Y-126551D02*
X1221516D01*
X1220861Y-124509D01*
X1219769Y-123343D01*
X1218241Y-122760D01*
X1216712Y-123051D01*
X1215402Y-123926D01*
X1214529Y-125968D01*
X1214092Y-127718D01*
Y-129468D01*
X1214529Y-131218D01*
X1215621Y-132968D01*
X1216931Y-134134D01*
X1218459Y-134426D01*
X1219987Y-133843D01*
X1221516Y-132093D01*
M02*
